(kicad_pcb
	(version 20260206)
	(generator "pcbnew")
	(generator_version "10.0")
	(general
		(thickness 1.6)
		(legacy_teardrops no)
	)
	(paper "A4")
	(title_block
		(title "01162023_DA0F0TEBIF0_F0T_Expander_BD_F_brd_V02_OCP.brd")
		(comment 1 "Grand Teton / footprint 383 of 9728 (J11), pads 77-138 of 138")
	)
	(layers
		(0 "F.Cu" signal "TOP")
		(4 "In1.Cu" signal "GND")
		(6 "In2.Cu" signal "VCC")
		(8 "In3.Cu" signal "VCC1")
		(10 "In4.Cu" signal "GND1")
		(12 "In5.Cu" signal "IN1")
		(14 "In6.Cu" signal "GND2")
		(16 "In7.Cu" signal "IN2")
		(18 "In8.Cu" signal "GND3")
		(20 "In9.Cu" signal "IN3")
		(22 "In10.Cu" signal "GND4")
		(24 "In11.Cu" signal "IN4")
		(26 "In12.Cu" signal "GND5")
		(28 "In13.Cu" signal "IN5")
		(30 "In14.Cu" signal "GND6")
		(32 "In15.Cu" signal "IN6")
		(34 "In16.Cu" signal "GND7")
		(2 "B.Cu" signal "BOTTOM")
		(9 "F.Adhes" user "F.Adhesive")
		(11 "B.Adhes" user "B.Adhesive")
		(13 "F.Paste" user "Package Geometry/Pastemask Top")
		(15 "B.Paste" user "Package Geometry/Pastemask Bottom")
		(5 "F.SilkS" user "Ref Des/Silkscreen Top")
		(7 "B.SilkS" user "Ref Des/Silkscreen Bottom")
		(1 "F.Mask" user "Board Geometry/Soldermask Top")
		(3 "B.Mask" user "Board Geometry/Soldermask Bottom")
		(17 "Dwgs.User" user "User.Drawings")
		(19 "Cmts.User" user "User.Comments")
		(21 "Eco1.User" user "User.Eco1")
		(23 "Eco2.User" user "User.Eco2")
		(25 "Edge.Cuts" user "Board Geometry/Outline")
		(27 "Margin" user)
		(31 "F.CrtYd" user "Package Geometry/Place Bound Top")
		(29 "B.CrtYd" user "Package Geometry/Place Bound Bottom")
		(35 "F.Fab" user "Ref Des/Assembly Top")
		(33 "B.Fab" user "Ref Des/Assembly Bottom")
	)
	(footprint ""
		(layer "F.Cu")
		(at 71.90994 -412.090108)
		(property "Reference" "J11"
			(at -5.90423 3.675888 90)
			(unlocked yes)
			(layer "F.SilkS")
			(effects
				(font
					(size 2.032 1.524)
					(thickness 0.1524)
				)
				(justify left)
			)
		)
		(property "Value" ""
			(at 0 0 0)
			(layer "F.Fab")
			(effects
				(font
					(size 1.27 1.27)
				)
			)
		)
		(duplicate_pad_numbers_are_jumpers no)
		(pad "N2_9" thru_hole circle
			(at 17.599914 27.29992 180)
			(size 0.906272 0.906272)
			(drill 0.499872)
			(layers "*.Cu" "*.Mask")
			(remove_unused_layers no)
			(net "GND")
			(clearance 0.0508)
			(thermal_gap 0.0508)
		)
		(pad "N10" thru_hole circle
			(at 19.800062 27.500072 180)
			(size 0.71628 0.71628)
			(drill 0.30988)
			(layers "*.Cu" "*.Mask")
			(remove_unused_layers no)
			(net "CLK_100M_MB_1_DN")
			(clearance 0.0508)
			(thermal_gap 0.0508)
		)
		(pad "O9" thru_hole circle
			(at 17.599914 28.599892 180)
			(size 0.71628 0.71628)
			(drill 0.30988)
			(layers "*.Cu" "*.Mask")
			(remove_unused_layers no)
			(net "CLK_100M_MB_0_DN")
			(clearance 0.0508)
			(thermal_gap 0.0508)
		)
		(pad "O10" thru_hole circle
			(at 19.800062 28.800044 180)
			(size 0.71628 0.71628)
			(drill 0.30988)
			(layers "*.Cu" "*.Mask")
			(remove_unused_layers no)
			(net "CLK_100M_MB_1_DP")
			(clearance 0.0508)
			(thermal_gap 0.0508)
		)
		(pad "P2" thru_hole circle
			(at 2.199894 30.100016 180)
			(size 0.906272 0.906272)
			(drill 0.499872)
			(layers "*.Cu" "*.Mask")
			(remove_unused_layers no)
			(net "GND")
			(clearance 0.0508)
			(thermal_gap 0.0508)
		)
		(pad "P4" thru_hole circle
			(at 6.599936 30.100016 180)
			(size 0.906272 0.906272)
			(drill 0.499872)
			(layers "*.Cu" "*.Mask")
			(remove_unused_layers no)
			(net "GND")
			(clearance 0.0508)
			(thermal_gap 0.0508)
		)
		(pad "P6" thru_hole circle
			(at 10.999978 30.100016 180)
			(size 0.906272 0.906272)
			(drill 0.499872)
			(layers "*.Cu" "*.Mask")
			(remove_unused_layers no)
			(net "GND")
			(clearance 0.0508)
			(thermal_gap 0.0508)
		)
		(pad "P8" thru_hole circle
			(at 15.40002 30.100016 180)
			(size 0.906272 0.906272)
			(drill 0.499872)
			(layers "*.Cu" "*.Mask")
			(remove_unused_layers no)
			(net "GND")
			(clearance 0.0508)
			(thermal_gap 0.0508)
		)
		(pad "P9" thru_hole circle
			(at 17.599914 29.900118 180)
			(size 0.71628 0.71628)
			(drill 0.30988)
			(layers "*.Cu" "*.Mask")
			(remove_unused_layers no)
			(net "CLK_100M_MB_0_DP")
			(clearance 0.0508)
			(thermal_gap 0.0508)
		)
		(pad "P10" thru_hole circle
			(at 19.800062 30.100016 180)
			(size 0.906272 0.906272)
			(drill 0.499872)
			(layers "*.Cu" "*.Mask")
			(remove_unused_layers no)
			(net "GND")
			(clearance 0.0508)
			(thermal_gap 0.0508)
		)
		(pad "Q1" thru_hole circle
			(at 0 31.20009 180)
			(size 0.906272 0.906272)
			(drill 0.499872)
			(layers "*.Cu" "*.Mask")
			(remove_unused_layers no)
			(net "GND")
			(clearance 0.0508)
			(thermal_gap 0.0508)
		)
		(pad "Q3" thru_hole circle
			(at 4.400042 31.20009 180)
			(size 0.906272 0.906272)
			(drill 0.499872)
			(layers "*.Cu" "*.Mask")
			(remove_unused_layers no)
			(net "GND")
			(clearance 0.0508)
			(thermal_gap 0.0508)
		)
		(pad "Q5" thru_hole circle
			(at 8.800084 31.20009 180)
			(size 0.906272 0.906272)
			(drill 0.499872)
			(layers "*.Cu" "*.Mask")
			(remove_unused_layers no)
			(net "GND")
			(clearance 0.0508)
			(thermal_gap 0.0508)
		)
		(pad "Q7" thru_hole circle
			(at 13.199872 31.20009 180)
			(size 0.906272 0.906272)
			(drill 0.499872)
			(layers "*.Cu" "*.Mask")
			(remove_unused_layers no)
			(net "GND")
			(clearance 0.0508)
			(thermal_gap 0.0508)
		)
		(pad "Q9" thru_hole circle
			(at 17.599914 31.20009 180)
			(size 0.906272 0.906272)
			(drill 0.499872)
			(layers "*.Cu" "*.Mask")
			(remove_unused_layers no)
			(net "GND")
			(clearance 0.0508)
			(thermal_gap 0.0508)
		)
		(pad "Q10" thru_hole circle
			(at 19.800062 31.399988 180)
			(size 0.71628 0.71628)
			(drill 0.30988)
			(layers "*.Cu" "*.Mask")
			(remove_unused_layers no)
			(net "SMB_GPU_1_SCL")
			(clearance 0.0508)
			(thermal_gap 0.0508)
		)
		(pad "R9" thru_hole circle
			(at 17.599914 32.500062 180)
			(size 0.71628 0.71628)
			(drill 0.30988)
			(layers "*.Cu" "*.Mask")
			(remove_unused_layers no)
			(net "SMB_GPU_2_SCL")
			(clearance 0.0508)
			(thermal_gap 0.0508)
		)
		(pad "R10" thru_hole circle
			(at 19.800062 32.69996 180)
			(size 0.71628 0.71628)
			(drill 0.30988)
			(layers "*.Cu" "*.Mask")
			(remove_unused_layers no)
			(net "SMB_GPU_1_SDA")
			(clearance 0.0508)
			(thermal_gap 0.0508)
		)
		(pad "S2" thru_hole circle
			(at 2.199894 33.999932 180)
			(size 0.906272 0.906272)
			(drill 0.499872)
			(layers "*.Cu" "*.Mask")
			(remove_unused_layers no)
			(net "GND")
			(clearance 0.0508)
			(thermal_gap 0.0508)
		)
		(pad "S4" thru_hole circle
			(at 6.599936 33.999932 180)
			(size 0.906272 0.906272)
			(drill 0.499872)
			(layers "*.Cu" "*.Mask")
			(remove_unused_layers no)
			(net "GND")
			(clearance 0.0508)
			(thermal_gap 0.0508)
		)
		(pad "S6" thru_hole circle
			(at 10.999978 33.999932 180)
			(size 0.906272 0.906272)
			(drill 0.499872)
			(layers "*.Cu" "*.Mask")
			(remove_unused_layers no)
			(net "GND")
			(clearance 0.0508)
			(thermal_gap 0.0508)
		)
		(pad "S8" thru_hole circle
			(at 15.40002 33.999932 180)
			(size 0.906272 0.906272)
			(drill 0.499872)
			(layers "*.Cu" "*.Mask")
			(remove_unused_layers no)
			(net "GND")
			(clearance 0.0508)
			(thermal_gap 0.0508)
		)
		(pad "S9" thru_hole circle
			(at 17.599914 33.800034 180)
			(size 0.71628 0.71628)
			(drill 0.30988)
			(layers "*.Cu" "*.Mask")
			(remove_unused_layers no)
			(net "SMB_GPU_2_SDA")
			(clearance 0.0508)
			(thermal_gap 0.0508)
		)
		(pad "S10" thru_hole circle
			(at 19.800062 33.999932 180)
			(size 0.906272 0.906272)
			(drill 0.499872)
			(layers "*.Cu" "*.Mask")
			(remove_unused_layers no)
			(net "GND")
			(clearance 0.0508)
			(thermal_gap 0.0508)
		)
		(pad "T1" thru_hole circle
			(at 0 35.100006 180)
			(size 0.906272 0.906272)
			(drill 0.499872)
			(layers "*.Cu" "*.Mask")
			(remove_unused_layers no)
			(net "GND")
			(clearance 0.0508)
			(thermal_gap 0.0508)
		)
		(pad "T3" thru_hole circle
			(at 4.400042 35.100006 180)
			(size 0.906272 0.906272)
			(drill 0.499872)
			(layers "*.Cu" "*.Mask")
			(remove_unused_layers no)
			(net "GND")
			(clearance 0.0508)
			(thermal_gap 0.0508)
		)
		(pad "T5" thru_hole circle
			(at 8.800084 35.100006 180)
			(size 0.906272 0.906272)
			(drill 0.499872)
			(layers "*.Cu" "*.Mask")
			(remove_unused_layers no)
			(net "GND")
			(clearance 0.0508)
			(thermal_gap 0.0508)
		)
		(pad "T7" thru_hole circle
			(at 13.199872 35.100006 180)
			(size 0.906272 0.906272)
			(drill 0.499872)
			(layers "*.Cu" "*.Mask")
			(remove_unused_layers no)
			(net "GND")
			(clearance 0.0508)
			(thermal_gap 0.0508)
		)
		(pad "T9" thru_hole circle
			(at 17.599914 35.100006 180)
			(size 0.906272 0.906272)
			(drill 0.499872)
			(layers "*.Cu" "*.Mask")
			(remove_unused_layers no)
			(net "GND")
			(clearance 0.0508)
			(thermal_gap 0.0508)
		)
		(pad "T10" thru_hole circle
			(at 19.800062 35.299904 180)
			(size 0.71628 0.71628)
			(drill 0.30988)
			(layers "*.Cu" "*.Mask")
			(remove_unused_layers no)
			(net "Net_619")
			(clearance 0.0508)
			(thermal_gap 0.0508)
		)
		(pad "U9" thru_hole circle
			(at 17.599914 36.399978 180)
			(size 0.71628 0.71628)
			(drill 0.30988)
			(layers "*.Cu" "*.Mask")
			(remove_unused_layers no)
			(net "Net_620")
			(clearance 0.0508)
			(thermal_gap 0.0508)
		)
		(pad "U10" thru_hole circle
			(at 19.800062 36.599876 180)
			(size 0.71628 0.71628)
			(drill 0.30988)
			(layers "*.Cu" "*.Mask")
			(remove_unused_layers no)
			(net "Net_621")
			(clearance 0.0508)
			(thermal_gap 0.0508)
		)
		(pad "V2" thru_hole circle
			(at 2.199894 37.900102 180)
			(size 0.906272 0.906272)
			(drill 0.499872)
			(layers "*.Cu" "*.Mask")
			(remove_unused_layers no)
			(net "GND")
			(clearance 0.0508)
			(thermal_gap 0.0508)
		)
		(pad "V4" thru_hole circle
			(at 6.599936 37.900102 180)
			(size 0.906272 0.906272)
			(drill 0.499872)
			(layers "*.Cu" "*.Mask")
			(remove_unused_layers no)
			(net "GND")
			(clearance 0.0508)
			(thermal_gap 0.0508)
		)
		(pad "V6" thru_hole circle
			(at 10.999978 37.900102 180)
			(size 0.906272 0.906272)
			(drill 0.499872)
			(layers "*.Cu" "*.Mask")
			(remove_unused_layers no)
			(net "GND")
			(clearance 0.0508)
			(thermal_gap 0.0508)
		)
		(pad "V8" thru_hole circle
			(at 15.40002 37.900102 180)
			(size 0.906272 0.906272)
			(drill 0.499872)
			(layers "*.Cu" "*.Mask")
			(remove_unused_layers no)
			(net "GND")
			(clearance 0.0508)
			(thermal_gap 0.0508)
		)
		(pad "V9" thru_hole circle
			(at 17.599914 37.69995 180)
			(size 0.71628 0.71628)
			(drill 0.30988)
			(layers "*.Cu" "*.Mask")
			(remove_unused_layers no)
			(net "Net_624")
			(clearance 0.0508)
			(thermal_gap 0.0508)
		)
		(pad "V10" thru_hole circle
			(at 19.800062 37.900102 180)
			(size 0.906272 0.906272)
			(drill 0.499872)
			(layers "*.Cu" "*.Mask")
			(remove_unused_layers no)
			(net "GND")
			(clearance 0.0508)
			(thermal_gap 0.0508)
		)
		(pad "W1" thru_hole circle
			(at 0 38.999922 180)
			(size 0.906272 0.906272)
			(drill 0.499872)
			(layers "*.Cu" "*.Mask")
			(remove_unused_layers no)
			(net "GND")
			(clearance 0.0508)
			(thermal_gap 0.0508)
		)
		(pad "W3" thru_hole circle
			(at 4.400042 38.999922 180)
			(size 0.906272 0.906272)
			(drill 0.499872)
			(layers "*.Cu" "*.Mask")
			(remove_unused_layers no)
			(net "GND")
			(clearance 0.0508)
			(thermal_gap 0.0508)
		)
		(pad "W5" thru_hole circle
			(at 8.800084 38.999922 180)
			(size 0.906272 0.906272)
			(drill 0.499872)
			(layers "*.Cu" "*.Mask")
			(remove_unused_layers no)
			(net "GND")
			(clearance 0.0508)
			(thermal_gap 0.0508)
		)
		(pad "W7" thru_hole circle
			(at 13.199872 38.999922 180)
			(size 0.906272 0.906272)
			(drill 0.499872)
			(layers "*.Cu" "*.Mask")
			(remove_unused_layers no)
			(net "GND")
			(clearance 0.0508)
			(thermal_gap 0.0508)
		)
		(pad "W9" thru_hole circle
			(at 17.599914 38.999922 180)
			(size 0.906272 0.906272)
			(drill 0.499872)
			(layers "*.Cu" "*.Mask")
			(remove_unused_layers no)
			(net "GND")
			(clearance 0.0508)
			(thermal_gap 0.0508)
		)
		(pad "W10" thru_hole circle
			(at 19.800062 39.200074 180)
			(size 0.71628 0.71628)
			(drill 0.30988)
			(layers "*.Cu" "*.Mask")
			(remove_unused_layers no)
			(net "Net_618")
			(clearance 0.0508)
			(thermal_gap 0.0508)
		)
		(pad "X9" thru_hole circle
			(at 17.599914 40.299894 180)
			(size 0.71628 0.71628)
			(drill 0.30988)
			(layers "*.Cu" "*.Mask")
			(remove_unused_layers no)
			(net "Net_625")
			(clearance 0.0508)
			(thermal_gap 0.0508)
		)
		(pad "X10" thru_hole circle
			(at 19.800062 40.500046 180)
			(size 0.71628 0.71628)
			(drill 0.30988)
			(layers "*.Cu" "*.Mask")
			(remove_unused_layers no)
			(net "Net_622")
			(clearance 0.0508)
			(thermal_gap 0.0508)
		)
		(pad "Y2" thru_hole circle
			(at 2.199894 41.800018 180)
			(size 0.906272 0.906272)
			(drill 0.499872)
			(layers "*.Cu" "*.Mask")
			(remove_unused_layers no)
			(net "GND")
			(clearance 0.0508)
			(thermal_gap 0.0508)
		)
		(pad "Y4" thru_hole circle
			(at 6.599936 41.800018 180)
			(size 0.906272 0.906272)
			(drill 0.499872)
			(layers "*.Cu" "*.Mask")
			(remove_unused_layers no)
			(net "GND")
			(clearance 0.0508)
			(thermal_gap 0.0508)
		)
		(pad "Y6" thru_hole circle
			(at 10.999978 41.800018 180)
			(size 0.906272 0.906272)
			(drill 0.499872)
			(layers "*.Cu" "*.Mask")
			(remove_unused_layers no)
			(net "GND")
			(clearance 0.0508)
			(thermal_gap 0.0508)
		)
		(pad "Y8" thru_hole circle
			(at 15.40002 41.800018 180)
			(size 0.906272 0.906272)
			(drill 0.499872)
			(layers "*.Cu" "*.Mask")
			(remove_unused_layers no)
			(net "GND")
			(clearance 0.0508)
			(thermal_gap 0.0508)
		)
		(pad "Y9" thru_hole circle
			(at 17.599914 41.60012 180)
			(size 0.71628 0.71628)
			(drill 0.30988)
			(layers "*.Cu" "*.Mask")
			(remove_unused_layers no)
			(net "Net_623")
			(clearance 0.0508)
			(thermal_gap 0.0508)
		)
		(pad "Y10" thru_hole circle
			(at 19.800062 41.800018 180)
			(size 0.906272 0.906272)
			(drill 0.499872)
			(layers "*.Cu" "*.Mask")
			(remove_unused_layers no)
			(net "GND")
			(clearance 0.0508)
			(thermal_gap 0.0508)
		)
		(pad "Z1" thru_hole circle
			(at 0 42.900092 180)
			(size 0.906272 0.906272)
			(drill 0.499872)
			(layers "*.Cu" "*.Mask")
			(remove_unused_layers no)
			(net "GND")
			(clearance 0.0508)
			(thermal_gap 0.0508)
		)
		(pad "Z2" thru_hole circle
			(at 2.199894 43.09999 180)
			(size 0.71628 0.71628)
			(drill 0.30988)
			(layers "*.Cu" "*.Mask")
			(remove_unused_layers no)
			(net "PRSNT_GPU_D_R_N")
			(clearance 0.0508)
			(thermal_gap 0.0508)
		)
		(pad "Z3" thru_hole circle
			(at 4.400042 42.900092 180)
			(size 0.906272 0.906272)
			(drill 0.499872)
			(layers "*.Cu" "*.Mask")
			(remove_unused_layers no)
			(net "GND")
			(clearance 0.0508)
			(thermal_gap 0.0508)
		)
		(pad "Z4" thru_hole circle
			(at 6.599936 43.09999 180)
			(size 0.71628 0.71628)
			(drill 0.30988)
			(layers "*.Cu" "*.Mask")
			(remove_unused_layers no)
			(net "GPU_BASE_PWR_EN")
			(clearance 0.0508)
			(thermal_gap 0.0508)
		)
		(pad "Z5" thru_hole circle
			(at 8.800084 42.900092 180)
			(size 0.906272 0.906272)
			(drill 0.499872)
			(layers "*.Cu" "*.Mask")
			(remove_unused_layers no)
			(net "GND")
			(clearance 0.0508)
			(thermal_gap 0.0508)
		)
		(pad "Z6" thru_hole circle
			(at 10.999978 43.09999 180)
			(size 0.71628 0.71628)
			(drill 0.30988)
			(layers "*.Cu" "*.Mask")
			(remove_unused_layers no)
			(net "GPU_BASE_PWR_GD_R")
			(clearance 0.0508)
			(thermal_gap 0.0508)
		)
		(pad "Z7" thru_hole circle
			(at 13.199872 42.900092 180)
			(size 0.906272 0.906272)
			(drill 0.499872)
			(layers "*.Cu" "*.Mask")
			(remove_unused_layers no)
			(net "GND")
			(clearance 0.0508)
			(thermal_gap 0.0508)
		)
		(pad "Z8" thru_hole circle
			(at 15.40002 43.09999 180)
			(size 0.71628 0.71628)
			(drill 0.30988)
			(layers "*.Cu" "*.Mask")
			(remove_unused_layers no)
			(net "GPU_BASE_ID1")
			(clearance 0.0508)
			(thermal_gap 0.0508)
		)
		(pad "Z9" thru_hole circle
			(at 17.599914 42.900092 180)
			(size 0.906272 0.906272)
			(drill 0.499872)
			(layers "*.Cu" "*.Mask")
			(remove_unused_layers no)
			(net "GND")
			(clearance 0.0508)
			(thermal_gap 0.0508)
		)
		(pad "Z10" thru_hole circle
			(at 19.800062 43.09999 180)
			(size 0.71628 0.71628)
			(drill 0.30988)
			(layers "*.Cu" "*.Mask")
			(remove_unused_layers no)
			(net "RST_MB_PERST_0_N")
			(clearance 0.0508)
			(thermal_gap 0.0508)
		)
	)
)
